FILE_TYPE = CONNECTIVITY;
{Allegro Design Entry HDL 17.4-2019 S026 (4007227) 1/17/2022}
"PAGE_NUMBER" = 352;
0"NC";
1"P5E_CPU0_P2_TX_C_DN<15:8>";
2"P5E_CPU0_P2_TX_C_DP<15:8>";
3"P5E_CPU0_P2_TX_DN<15:8>";
4"P5E_CPU0_P2_TX_DP<15:8>";
5"P5E_CPU0_P2_TX_C_DP<7:0>";
6"P5E_CPU0_P2_TX_C_DN<7:0>";
7"P5E_CPU0_P3_TX_DP<7:0>";
8"P5E_CPU0_P3_TX_DN<7:0>";
9"P5E_CPU0_P3_TX_C_DP<7:0>";
10"P5E_CPU0_P3_TX_C_DN<7:0>";
11"P5E_CPU0_P3_TX_C_DP<15:8>";
12"P5E_CPU0_P3_TX_C_DN<15:8>";
13"P5E_CPU0_P3_TX_DN<15:8>";
14"P5E_CPU0_P3_TX_DP<15:8>";
15"P5E_CPU0_P2_TX_DN<7:0>";
16"P5E_CPU0_P2_TX_DP<7:0>";
17"P5E_CPU0_P3_TX_C_DP<12>";
18"P5E_CPU0_P3_TX_DP<9>";
19"P5E_CPU0_P2_TX_C_DP<9>";
20"P5E_CPU0_P2_TX_DN<8>";
21"P5E_CPU0_P2_TX_DP<8>";
22"P5E_CPU0_P2_TX_C_DP<8>";
23"P5E_CPU0_P2_TX_C_DP<12>";
24"P5E_CPU0_P2_TX_C_DN<11>";
25"P5E_CPU0_P2_TX_DN<10>";
26"P5E_CPU0_P2_TX_DP<10>";
27"P5E_CPU0_P2_TX_DP<9>";
28"P5E_CPU0_P2_TX_DN<15>";
29"P5E_CPU0_P2_TX_DP<15>";
30"P5E_CPU0_P2_TX_DP<14>";
31"P5E_CPU0_P2_TX_DN<11>";
32"P5E_CPU0_P2_TX_C_DN<4>";
33"P5E_CPU0_P2_TX_C_DP<4>";
34"P5E_CPU0_P2_TX_C_DN<1>";
35"P5E_CPU0_P2_TX_C_DP<7>";
36"P5E_CPU0_P2_TX_C_DN<7>";
37"P5E_CPU0_P2_TX_C_DP<0>";
38"P5E_CPU0_P2_TX_DP<3>";
39"P5E_CPU0_P2_TX_DP<0>";
40"P5E_CPU0_P2_TX_C_DN<0>";
41"P5E_CPU0_P2_TX_C_DP<3>";
42"P5E_CPU0_P2_TX_DP<5>";
43"P5E_CPU0_P2_TX_DN<4>";
44"P5E_CPU0_P2_TX_DN<2>";
45"P5E_CPU0_P2_TX_DP<2>";
46"P5E_CPU0_P2_TX_DP<1>";
47"P5E_CPU0_P2_TX_DN<6>";
48"P5E_CPU0_P2_TX_DP<7>";
49"P5E_CPU0_P2_TX_DN<0>";
50"P5E_CPU0_P2_TX_DN<3>";
51"P5E_CPU0_P2_TX_DP<6>";
52"P5E_CPU0_P2_TX_DN<5>";
53"P5E_CPU0_P2_TX_DN<7>";
54"P5E_CPU0_P2_TX_DP<4>";
55"P5E_CPU0_P2_TX_DN<1>";
56"P5E_CPU0_P2_TX_C_DN<3>";
57"P5E_CPU0_P2_TX_C_DN<2>";
58"P5E_CPU0_P2_TX_C_DN<6>";
59"P5E_CPU0_P2_TX_DN<9>";
60"P5E_CPU0_P2_TX_DN<13>";
61"P5E_CPU0_P2_TX_DN<14>";
62"P5E_CPU0_P2_TX_DP<11>";
63"P5E_CPU0_P2_TX_DP<13>";
64"P5E_CPU0_P2_TX_C_DN<9>";
65"P5E_CPU0_P2_TX_C_DN<8>";
66"P5E_CPU0_P2_TX_C_DN<10>";
67"P5E_CPU0_P2_TX_C_DN<12>";
68"P5E_CPU0_P2_TX_C_DP<10>";
69"P5E_CPU0_P2_TX_C_DP<11>";
70"P5E_CPU0_P2_TX_C_DP<2>";
71"P5E_CPU0_P2_TX_C_DP<1>";
72"P5E_CPU0_P2_TX_C_DP<5>";
73"P5E_CPU0_P3_TX_DP<0>";
74"P5E_CPU0_P3_TX_DP<5>";
75"P5E_CPU0_P3_TX_DP<3>";
76"P5E_CPU0_P3_TX_DP<1>";
77"P5E_CPU0_P3_TX_DP<2>";
78"P5E_CPU0_P3_TX_DP<6>";
79"P5E_CPU0_P3_TX_DP<7>";
80"P5E_CPU0_P3_TX_DN<1>";
81"P5E_CPU0_P3_TX_DN<0>";
82"P5E_CPU0_P3_TX_DN<4>";
83"P5E_CPU0_P3_TX_DN<5>";
84"P5E_CPU0_P3_TX_DN<6>";
85"P5E_CPU0_P3_TX_DN<7>";
86"P5E_CPU0_P3_TX_DP<12>";
87"P5E_CPU0_P3_TX_DP<10>";
88"P5E_CPU0_P3_TX_DP<11>";
89"P5E_CPU0_P3_TX_DP<8>";
90"P5E_CPU0_P3_TX_DP<13>";
91"P5E_CPU0_P3_TX_DP<15>";
92"P5E_CPU0_P3_TX_DP<14>";
93"P5E_CPU0_P3_TX_DN<12>";
94"P5E_CPU0_P3_TX_DN<10>";
95"P5E_CPU0_P3_TX_DN<9>";
96"P5E_CPU0_P3_TX_DN<11>";
97"P5E_CPU0_P3_TX_DN<8>";
98"P5E_CPU0_P3_TX_DN<15>";
99"P5E_CPU0_P3_TX_DN<13>";
100"P5E_CPU0_P3_TX_DN<14>";
101"P5E_CPU0_P3_TX_C_DP<13>";
102"P5E_CPU0_P3_TX_C_DN<13>";
103"P5E_CPU0_P3_TX_C_DP<5>";
104"P5E_CPU0_P3_TX_C_DP<6>";
105"P5E_CPU0_P3_TX_C_DP<8>";
106"P5E_CPU0_P3_TX_C_DN<1>";
107"P5E_CPU0_P3_TX_C_DN<2>";
108"P5E_CPU0_P3_TX_C_DN<3>";
109"P5E_CPU0_P3_TX_C_DP<4>";
110"P5E_CPU0_P3_TX_C_DP<2>";
111"P5E_CPU0_P3_TX_C_DP<3>";
112"P5E_CPU0_P3_TX_C_DN<4>";
113"P5E_CPU0_P3_TX_C_DN<5>";
114"P5E_CPU0_P3_TX_C_DN<6>";
115"P5E_CPU0_P3_TX_C_DN<7>";
116"P5E_CPU0_P3_TX_C_DP<7>";
117"P5E_CPU0_P3_TX_C_DN<9>";
118"P5E_CPU0_P3_TX_C_DN<8>";
119"P5E_CPU0_P3_TX_C_DN<10>";
120"P5E_CPU0_P3_TX_C_DN<11>";
121"P5E_CPU0_P3_TX_C_DN<12>";
122"P5E_CPU0_P3_TX_C_DP<9>";
123"P5E_CPU0_P3_TX_C_DP<10>";
124"P5E_CPU0_P3_TX_C_DP<11>";
125"P5E_CPU0_P3_TX_C_DN<14>";
126"P5E_CPU0_P3_TX_C_DN<15>";
127"P5E_CPU0_P3_TX_C_DP<15>";
128"P5E_CPU0_P3_TX_C_DP<14>";
129"P5E_CPU0_P3_TX_C_DN<0>";
130"P5E_CPU0_P3_TX_C_DP<0>";
131"P5E_CPU0_P3_TX_C_DP<1>";
132"P5E_CPU0_P3_TX_DN<2>";
133"P5E_CPU0_P3_TX_DN<3>";
134"P5E_CPU0_P3_TX_DP<4>";
135"P5E_CPU0_P2_TX_C_DN<5>";
136"P5E_CPU0_P2_TX_C_DP<6>";
137"P5E_CPU0_P2_TX_DP<12>";
138"P5E_CPU0_P2_TX_DN<12>";
139"P5E_CPU0_P2_TX_C_DP<13>";
140"P5E_CPU0_P2_TX_C_DN<13>";
141"P5E_CPU0_P2_TX_C_DP<14>";
142"P5E_CPU0_P2_TX_C_DN<14>";
143"P5E_CPU0_P2_TX_C_DP<15>";
144"P5E_CPU0_P2_TX_C_DN<15>";
%"TAP"
"1","(-1375,175)","2","standard","I10";
;
CDS_LIB"standard"
BODY_TYPE"PLUMBING"
HDL_TAP"TRUE";
"B \NAC \NWC"15;
"S \NAC"
BN"0"49;
%"TAP"
"1","(100,2700)","0","standard","I100";
;
CDS_LIB"standard"
BODY_TYPE"PLUMBING"
HDL_TAP"TRUE";
"B \NAC \NWC"2;
"S \NAC"
BN"11"69;
%"TAP"
"1","(100,2900)","0","standard","I101";
;
CDS_LIB"standard"
BODY_TYPE"PLUMBING"
HDL_TAP"TRUE";
"B \NAC \NWC"2;
"S \NAC"
BN"12"23;
%"TAP"
"1","(100,3100)","0","standard","I102";
;
CDS_LIB"standard"
BODY_TYPE"PLUMBING"
HDL_TAP"TRUE";
"B \NAC \NWC"2;
"S \NAC"
BN"13"139;
%"TAP"
"1","(100,3300)","0","standard","I103";
;
CDS_LIB"standard"
BODY_TYPE"PLUMBING"
HDL_TAP"TRUE";
"B \NAC \NWC"2;
"S \NAC"
BN"14"141;
%"TAP"
"1","(100,3500)","0","standard","I104";
;
CDS_LIB"standard"
BODY_TYPE"PLUMBING"
HDL_TAP"TRUE";
"B \NAC \NWC"2;
"S \NAC"
BN"15"143;
%"TAP"
"1","(2850,125)","2","standard","I109";
;
CDS_LIB"standard"
BODY_TYPE"PLUMBING"
HDL_TAP"TRUE";
"B \NAC \NWC"7;
"S \NAC"
BN"0"73;
%"TAP"
"1","(-1375,375)","2","standard","I11";
;
CDS_LIB"standard"
BODY_TYPE"PLUMBING"
HDL_TAP"TRUE";
"B \NAC \NWC"15;
"S \NAC"
BN"1"55;
%"TAP"
"1","(2850,325)","2","standard","I110";
;
CDS_LIB"standard"
BODY_TYPE"PLUMBING"
HDL_TAP"TRUE";
"B \NAC \NWC"7;
"S \NAC"
BN"1"76;
%"TAP"
"1","(2850,525)","2","standard","I111";
;
CDS_LIB"standard"
BODY_TYPE"PLUMBING"
HDL_TAP"TRUE";
"B \NAC \NWC"7;
"S \NAC"
BN"2"77;
%"TAP"
"1","(2850,725)","2","standard","I112";
;
CDS_LIB"standard"
BODY_TYPE"PLUMBING"
HDL_TAP"TRUE";
"B \NAC \NWC"7;
"S \NAC"
BN"3"75;
%"TAP"
"1","(2850,925)","2","standard","I113";
;
CDS_LIB"standard"
BODY_TYPE"PLUMBING"
HDL_TAP"TRUE";
"B \NAC \NWC"7;
"S \NAC"
BN"4"134;
%"TAP"
"1","(2850,1325)","2","standard","I114";
;
CDS_LIB"standard"
BODY_TYPE"PLUMBING"
HDL_TAP"TRUE";
"B \NAC \NWC"7;
"S \NAC"
BN"6"78;
%"TAP"
"1","(2850,1525)","2","standard","I115";
;
CDS_LIB"standard"
BODY_TYPE"PLUMBING"
HDL_TAP"TRUE";
"B \NAC \NWC"7;
"S \NAC"
BN"7"79;
%"TAP"
"1","(3100,175)","2","standard","I116";
;
CDS_LIB"standard"
BODY_TYPE"PLUMBING"
HDL_TAP"TRUE";
"B \NAC \NWC"8;
"S \NAC"
BN"0"81;
%"TAP"
"1","(3100,375)","2","standard","I117";
;
CDS_LIB"standard"
BODY_TYPE"PLUMBING"
HDL_TAP"TRUE";
"B \NAC \NWC"8;
"S \NAC"
BN"1"80;
%"TAP"
"1","(3100,575)","2","standard","I118";
;
CDS_LIB"standard"
BODY_TYPE"PLUMBING"
HDL_TAP"TRUE";
"B \NAC \NWC"8;
"S \NAC"
BN"2"132;
%"TAP"
"1","(3100,775)","2","standard","I119";
;
CDS_LIB"standard"
BODY_TYPE"PLUMBING"
HDL_TAP"TRUE";
"B \NAC \NWC"8;
"S \NAC"
BN"3"133;
%"TAP"
"1","(-1375,575)","2","standard","I12";
;
CDS_LIB"standard"
BODY_TYPE"PLUMBING"
HDL_TAP"TRUE";
"B \NAC \NWC"15;
"S \NAC"
BN"2"44;
%"Q_CAP_DIFFBUS"
"2","(3825,125)","2","pure_quanta","I120";
;
LOCATION"C901"
$SEC"1"
CDS_SEC"1"
VALUE"DIFF BUS_0.22UF"
PIN_NAMES_ROTATE"TRUE"
CDS_LIB"pure_quanta"
CDS_LMAN_SYM_OUTLINE"-25,50,25,-50"
VOLTAGE"6.3V"
MATERIAL"X6S"
PACK_TYPE"C0201"
TOLERANCE"20%"
PART_NUMBER"SP_CH4221MEE01"
LOCATION"C901";
"2"
$PN"2"73;
"1"
$PN"1"130;
%"Q_CAP_DIFFBUS"
"2","(3825,175)","2","pure_quanta","I121";
;
LOCATION"C900"
$SEC"1"
CDS_SEC"1"
VALUE"DIFF BUS_0.22UF"
PIN_NAMES_ROTATE"TRUE"
CDS_LIB"pure_quanta"
CDS_LMAN_SYM_OUTLINE"-25,50,25,-50"
VOLTAGE"6.3V"
MATERIAL"X6S"
PACK_TYPE"C0201"
TOLERANCE"20%"
PART_NUMBER"SP_CH4221MEE01"
LOCATION"C900";
"2"
$PN"2"81;
"1"
$PN"1"129;
%"Q_CAP_DIFFBUS"
"2","(3825,325)","2","pure_quanta","I122";
;
LOCATION"C899"
$SEC"1"
CDS_SEC"1"
VALUE"DIFF BUS_0.22UF"
PIN_NAMES_ROTATE"TRUE"
CDS_LIB"pure_quanta"
CDS_LMAN_SYM_OUTLINE"-25,50,25,-50"
VOLTAGE"6.3V"
MATERIAL"X6S"
PACK_TYPE"C0201"
TOLERANCE"20%"
PART_NUMBER"SP_CH4221MEE01"
LOCATION"C899";
"2"
$PN"2"76;
"1"
$PN"1"131;
%"Q_CAP_DIFFBUS"
"2","(3825,525)","2","pure_quanta","I123";
;
LOCATION"C897"
$SEC"1"
CDS_SEC"1"
VALUE"DIFF BUS_0.22UF"
PIN_NAMES_ROTATE"TRUE"
CDS_LIB"pure_quanta"
CDS_LMAN_SYM_OUTLINE"-25,50,25,-50"
VOLTAGE"6.3V"
MATERIAL"X6S"
PACK_TYPE"C0201"
TOLERANCE"20%"
PART_NUMBER"SP_CH4221MEE01"
LOCATION"C897";
"2"
$PN"2"77;
"1"
$PN"1"110;
%"Q_CAP_DIFFBUS"
"2","(3825,575)","2","pure_quanta","I124";
;
LOCATION"C896"
$SEC"1"
CDS_SEC"1"
VALUE"DIFF BUS_0.22UF"
PIN_NAMES_ROTATE"TRUE"
CDS_LIB"pure_quanta"
CDS_LMAN_SYM_OUTLINE"-25,50,25,-50"
VOLTAGE"6.3V"
MATERIAL"X6S"
PACK_TYPE"C0201"
TOLERANCE"20%"
PART_NUMBER"SP_CH4221MEE01"
LOCATION"C896";
"2"
$PN"2"132;
"1"
$PN"1"107;
%"Q_CAP_DIFFBUS"
"2","(3825,725)","2","pure_quanta","I125";
;
LOCATION"C895"
$SEC"1"
CDS_SEC"1"
VALUE"DIFF BUS_0.22UF"
PIN_NAMES_ROTATE"TRUE"
CDS_LMAN_SYM_OUTLINE"-25,50,25,-50"
CDS_LIB"pure_quanta"
VOLTAGE"6.3V"
MATERIAL"X6S"
PACK_TYPE"C0201"
TOLERANCE"20%"
PART_NUMBER"SP_CH4221MEE01"
LOCATION"C895";
"2"
$PN"2"75;
"1"
$PN"1"111;
%"Q_CAP_DIFFBUS"
"2","(3825,775)","2","pure_quanta","I126";
;
LOCATION"C894"
$SEC"1"
CDS_SEC"1"
VALUE"DIFF BUS_0.22UF"
PIN_NAMES_ROTATE"TRUE"
CDS_LMAN_SYM_OUTLINE"-25,50,25,-50"
CDS_LIB"pure_quanta"
VOLTAGE"6.3V"
MATERIAL"X6S"
PACK_TYPE"C0201"
TOLERANCE"20%"
PART_NUMBER"SP_CH4221MEE01"
LOCATION"C894";
"2"
$PN"2"133;
"1"
$PN"1"108;
%"Q_CAP_DIFFBUS"
"2","(3825,975)","2","pure_quanta","I127";
;
LOCATION"C892"
$SEC"1"
CDS_SEC"1"
VALUE"DIFF BUS_0.22UF"
PIN_NAMES_ROTATE"TRUE"
CDS_LIB"pure_quanta"
CDS_LMAN_SYM_OUTLINE"-25,50,25,-50"
VOLTAGE"6.3V"
MATERIAL"X6S"
PACK_TYPE"C0201"
TOLERANCE"20%"
PART_NUMBER"SP_CH4221MEE01"
LOCATION"C892";
"2"
$PN"2"82;
"1"
$PN"1"112;
%"Q_CAP_DIFFBUS"
"2","(3825,925)","2","pure_quanta","I128";
;
LOCATION"C893"
$SEC"1"
CDS_SEC"1"
VALUE"DIFF BUS_0.22UF"
PIN_NAMES_ROTATE"TRUE"
CDS_LIB"pure_quanta"
CDS_LMAN_SYM_OUTLINE"-25,50,25,-50"
VOLTAGE"6.3V"
MATERIAL"X6S"
PACK_TYPE"C0201"
TOLERANCE"20%"
PART_NUMBER"SP_CH4221MEE01"
LOCATION"C893";
"2"
$PN"2"134;
"1"
$PN"1"109;
%"TAP"
"1","(3100,1175)","2","standard","I129";
;
CDS_LIB"standard"
BODY_TYPE"PLUMBING"
HDL_TAP"TRUE";
"B \NAC \NWC"8;
"S \NAC"
BN"5"83;
%"TAP"
"1","(-1375,775)","2","standard","I13";
;
CDS_LIB"standard"
BODY_TYPE"PLUMBING"
HDL_TAP"TRUE";
"B \NAC \NWC"15;
"S \NAC"
BN"3"50;
%"TAP"
"1","(3100,1375)","2","standard","I130";
;
CDS_LIB"standard"
BODY_TYPE"PLUMBING"
HDL_TAP"TRUE";
"B \NAC \NWC"8;
"S \NAC"
BN"6"84;
%"TAP"
"1","(3100,1575)","2","standard","I131";
;
CDS_LIB"standard"
BODY_TYPE"PLUMBING"
HDL_TAP"TRUE";
"B \NAC \NWC"8;
"S \NAC"
BN"7"85;
%"Q_CAP_DIFFBUS"
"2","(3825,1125)","2","pure_quanta","I132";
;
LOCATION"C891"
$SEC"1"
CDS_SEC"1"
VALUE"DIFF BUS_0.22UF"
PIN_NAMES_ROTATE"TRUE"
CDS_LIB"pure_quanta"
CDS_LMAN_SYM_OUTLINE"-25,50,25,-50"
VOLTAGE"6.3V"
MATERIAL"X6S"
PACK_TYPE"C0201"
TOLERANCE"20%"
PART_NUMBER"SP_CH4221MEE01"
LOCATION"C891";
"2"
$PN"2"74;
"1"
$PN"1"103;
%"Q_CAP_DIFFBUS"
"2","(3825,1175)","2","pure_quanta","I133";
;
LOCATION"C890"
$SEC"1"
CDS_SEC"1"
VALUE"DIFF BUS_0.22UF"
PIN_NAMES_ROTATE"TRUE"
CDS_LIB"pure_quanta"
CDS_LMAN_SYM_OUTLINE"-25,50,25,-50"
VOLTAGE"6.3V"
MATERIAL"X6S"
PACK_TYPE"C0201"
TOLERANCE"20%"
PART_NUMBER"SP_CH4221MEE01"
LOCATION"C890";
"2"
$PN"2"83;
"1"
$PN"1"113;
%"Q_CAP_DIFFBUS"
"2","(3825,1325)","2","pure_quanta","I134";
;
LOCATION"C889"
$SEC"1"
CDS_SEC"1"
VALUE"DIFF BUS_0.22UF"
PIN_NAMES_ROTATE"TRUE"
CDS_LIB"pure_quanta"
CDS_LMAN_SYM_OUTLINE"-25,50,25,-50"
VOLTAGE"6.3V"
MATERIAL"X6S"
PACK_TYPE"C0201"
TOLERANCE"20%"
PART_NUMBER"SP_CH4221MEE01"
LOCATION"C889";
"2"
$PN"2"78;
"1"
$PN"1"104;
%"Q_CAP_DIFFBUS"
"2","(3825,1375)","2","pure_quanta","I135";
;
LOCATION"C888"
$SEC"1"
CDS_SEC"1"
VALUE"DIFF BUS_0.22UF"
PIN_NAMES_ROTATE"TRUE"
CDS_LIB"pure_quanta"
CDS_LMAN_SYM_OUTLINE"-25,50,25,-50"
VOLTAGE"6.3V"
MATERIAL"X6S"
PACK_TYPE"C0201"
TOLERANCE"20%"
PART_NUMBER"SP_CH4221MEE01"
LOCATION"C888";
"2"
$PN"2"84;
"1"
$PN"1"114;
%"Q_CAP_DIFFBUS"
"2","(3825,1525)","2","pure_quanta","I136";
;
LOCATION"C887"
$SEC"1"
CDS_SEC"1"
VALUE"DIFF BUS_0.22UF"
PIN_NAMES_ROTATE"TRUE"
CDS_LIB"pure_quanta"
CDS_LMAN_SYM_OUTLINE"-25,50,25,-50"
VOLTAGE"6.3V"
MATERIAL"X6S"
PACK_TYPE"C0201"
TOLERANCE"20%"
PART_NUMBER"SP_CH4221MEE01"
LOCATION"C887";
"2"
$PN"2"79;
"1"
$PN"1"116;
%"Q_CAP_DIFFBUS"
"2","(3825,1575)","2","pure_quanta","I137";
;
LOCATION"C886"
$SEC"1"
CDS_SEC"1"
VALUE"DIFF BUS_0.22UF"
PIN_NAMES_ROTATE"TRUE"
CDS_LMAN_SYM_OUTLINE"-25,50,25,-50"
CDS_LIB"pure_quanta"
VOLTAGE"6.3V"
MATERIAL"X6S"
PACK_TYPE"C0201"
TOLERANCE"20%"
PART_NUMBER"SP_CH4221MEE01"
LOCATION"C886";
"2"
$PN"2"85;
"1"
$PN"1"115;
%"TAP"
"1","(2850,2100)","2","standard","I138";
;
CDS_LIB"standard"
BODY_TYPE"PLUMBING"
HDL_TAP"TRUE";
"B \NAC \NWC"14;
"S \NAC"
BN"8"89;
%"TAP"
"1","(2850,2300)","2","standard","I139";
;
CDS_LIB"standard"
BODY_TYPE"PLUMBING"
HDL_TAP"TRUE";
"B \NAC \NWC"14;
"S \NAC"
BN"9"18;
%"TAP"
"1","(-1375,975)","2","standard","I14";
;
CDS_LIB"standard"
BODY_TYPE"PLUMBING"
HDL_TAP"TRUE";
"B \NAC \NWC"15;
"S \NAC"
BN"4"43;
%"TAP"
"1","(2850,2500)","2","standard","I140";
;
CDS_LIB"standard"
BODY_TYPE"PLUMBING"
HDL_TAP"TRUE";
"B \NAC \NWC"14;
"S \NAC"
BN"10"87;
%"TAP"
"1","(2850,2700)","2","standard","I141";
;
CDS_LIB"standard"
BODY_TYPE"PLUMBING"
HDL_TAP"TRUE";
"B \NAC \NWC"14;
"S \NAC"
BN"11"88;
%"TAP"
"1","(2850,2900)","2","standard","I142";
;
CDS_LIB"standard"
BODY_TYPE"PLUMBING"
HDL_TAP"TRUE";
"B \NAC \NWC"14;
"S \NAC"
BN"12"86;
%"TAP"
"1","(2850,3100)","2","standard","I143";
;
CDS_LIB"standard"
BODY_TYPE"PLUMBING"
HDL_TAP"TRUE";
"B \NAC \NWC"14;
"S \NAC"
BN"13"90;
%"TAP"
"1","(2850,3300)","2","standard","I144";
;
CDS_LIB"standard"
BODY_TYPE"PLUMBING"
HDL_TAP"TRUE";
"B \NAC \NWC"14;
"S \NAC"
BN"14"92;
%"TAP"
"1","(2850,3500)","2","standard","I145";
;
CDS_LIB"standard"
BODY_TYPE"PLUMBING"
HDL_TAP"TRUE";
"B \NAC \NWC"14;
"S \NAC"
BN"15"91;
%"TAP"
"1","(3100,2150)","2","standard","I146";
;
CDS_LIB"standard"
BODY_TYPE"PLUMBING"
HDL_TAP"TRUE";
"B \NAC \NWC"13;
"S \NAC"
BN"8"97;
%"TAP"
"1","(3100,2350)","2","standard","I147";
;
CDS_LIB"standard"
BODY_TYPE"PLUMBING"
HDL_TAP"TRUE";
"B \NAC \NWC"13;
"S \NAC"
BN"9"95;
%"TAP"
"1","(3100,2550)","2","standard","I148";
;
CDS_LIB"standard"
BODY_TYPE"PLUMBING"
HDL_TAP"TRUE";
"B \NAC \NWC"13;
"S \NAC"
BN"10"94;
%"TAP"
"1","(3100,2750)","2","standard","I149";
;
CDS_LIB"standard"
BODY_TYPE"PLUMBING"
HDL_TAP"TRUE";
"B \NAC \NWC"13;
"S \NAC"
BN"11"96;
%"TAP"
"1","(-1625,1125)","2","standard","I15";
;
CDS_LIB"standard"
BODY_TYPE"PLUMBING"
HDL_TAP"TRUE";
"B \NAC \NWC"16;
"S \NAC"
BN"5"42;
%"TAP"
"1","(3100,2950)","2","standard","I150";
;
CDS_LIB"standard"
BODY_TYPE"PLUMBING"
HDL_TAP"TRUE";
"B \NAC \NWC"13;
"S \NAC"
BN"12"93;
%"Q_CAP_DIFFBUS"
"2","(3825,2150)","2","pure_quanta","I151";
;
LOCATION"C884"
$SEC"1"
CDS_SEC"1"
VALUE"DIFF BUS_0.22UF"
CDS_LMAN_SYM_OUTLINE"-25,50,25,-50"
CDS_LIB"pure_quanta"
PIN_NAMES_ROTATE"TRUE"
VOLTAGE"6.3V"
MATERIAL"X6S"
PACK_TYPE"C0201"
TOLERANCE"20%"
PART_NUMBER"SP_CH4221MEE01"
LOCATION"C884";
"2"
$PN"2"97;
"1"
$PN"1"118;
%"Q_CAP_DIFFBUS"
"2","(3825,2100)","2","pure_quanta","I152";
;
LOCATION"C885"
$SEC"1"
CDS_SEC"1"
VALUE"DIFF BUS_0.22UF"
CDS_LMAN_SYM_OUTLINE"-25,50,25,-50"
CDS_LIB"pure_quanta"
PIN_NAMES_ROTATE"TRUE"
VOLTAGE"6.3V"
MATERIAL"X6S"
PACK_TYPE"C0201"
TOLERANCE"20%"
PART_NUMBER"SP_CH4221MEE01"
LOCATION"C885";
"2"
$PN"2"89;
"1"
$PN"1"105;
%"Q_CAP_DIFFBUS"
"2","(3825,2300)","2","pure_quanta","I153";
;
LOCATION"C883"
$SEC"1"
CDS_SEC"1"
VALUE"DIFF BUS_0.22UF"
CDS_LMAN_SYM_OUTLINE"-25,50,25,-50"
CDS_LIB"pure_quanta"
PIN_NAMES_ROTATE"TRUE"
VOLTAGE"6.3V"
MATERIAL"X6S"
PACK_TYPE"C0201"
TOLERANCE"20%"
PART_NUMBER"SP_CH4221MEE01"
LOCATION"C883";
"2"
$PN"2"18;
"1"
$PN"1"122;
%"Q_CAP_DIFFBUS"
"2","(3825,2350)","2","pure_quanta","I154";
;
LOCATION"C882"
$SEC"1"
CDS_SEC"1"
VALUE"DIFF BUS_0.22UF"
CDS_LIB"pure_quanta"
CDS_LMAN_SYM_OUTLINE"-25,50,25,-50"
PIN_NAMES_ROTATE"TRUE"
VOLTAGE"6.3V"
MATERIAL"X6S"
PACK_TYPE"C0201"
TOLERANCE"20%"
PART_NUMBER"SP_CH4221MEE01"
LOCATION"C882";
"2"
$PN"2"95;
"1"
$PN"1"117;
%"Q_CAP_DIFFBUS"
"2","(3825,2500)","2","pure_quanta","I155";
;
LOCATION"C881"
$SEC"1"
CDS_SEC"1"
VALUE"DIFF BUS_0.22UF"
CDS_LMAN_SYM_OUTLINE"-25,50,25,-50"
CDS_LIB"pure_quanta"
PIN_NAMES_ROTATE"TRUE"
VOLTAGE"6.3V"
MATERIAL"X6S"
PACK_TYPE"C0201"
TOLERANCE"20%"
PART_NUMBER"SP_CH4221MEE01"
LOCATION"C881";
"2"
$PN"2"87;
"1"
$PN"1"123;
%"Q_CAP_DIFFBUS"
"2","(3825,2550)","2","pure_quanta","I156";
;
LOCATION"C880"
$SEC"1"
CDS_SEC"1"
VALUE"DIFF BUS_0.22UF"
CDS_LMAN_SYM_OUTLINE"-25,50,25,-50"
CDS_LIB"pure_quanta"
PIN_NAMES_ROTATE"TRUE"
VOLTAGE"6.3V"
MATERIAL"X6S"
PACK_TYPE"C0201"
TOLERANCE"20%"
PART_NUMBER"SP_CH4221MEE01"
LOCATION"C880";
"2"
$PN"2"94;
"1"
$PN"1"119;
%"Q_CAP_DIFFBUS"
"2","(3825,2750)","2","pure_quanta","I157";
;
LOCATION"C878"
$SEC"1"
CDS_SEC"1"
VALUE"DIFF BUS_0.22UF"
CDS_LIB"pure_quanta"
CDS_LMAN_SYM_OUTLINE"-25,50,25,-50"
PIN_NAMES_ROTATE"TRUE"
VOLTAGE"6.3V"
MATERIAL"X6S"
PACK_TYPE"C0201"
TOLERANCE"20%"
PART_NUMBER"SP_CH4221MEE01"
LOCATION"C878";
"2"
$PN"2"96;
"1"
$PN"1"120;
%"Q_CAP_DIFFBUS"
"2","(3825,2700)","2","pure_quanta","I158";
;
LOCATION"C879"
$SEC"1"
CDS_SEC"1"
VALUE"DIFF BUS_0.22UF"
CDS_LIB"pure_quanta"
CDS_LMAN_SYM_OUTLINE"-25,50,25,-50"
PIN_NAMES_ROTATE"TRUE"
VOLTAGE"6.3V"
MATERIAL"X6S"
PACK_TYPE"C0201"
TOLERANCE"20%"
PART_NUMBER"SP_CH4221MEE01"
LOCATION"C879";
"2"
$PN"2"88;
"1"
$PN"1"124;
%"Q_CAP_DIFFBUS"
"2","(3825,2900)","2","pure_quanta","I159";
;
LOCATION"C877"
$SEC"1"
CDS_SEC"1"
VALUE"DIFF BUS_0.22UF"
CDS_LMAN_SYM_OUTLINE"-25,50,25,-50"
CDS_LIB"pure_quanta"
PIN_NAMES_ROTATE"TRUE"
VOLTAGE"6.3V"
MATERIAL"X6S"
PACK_TYPE"C0201"
TOLERANCE"20%"
PART_NUMBER"SP_CH4221MEE01"
LOCATION"C877";
"2"
$PN"2"86;
"1"
$PN"1"17;
%"TAP"
"1","(-1625,1325)","2","standard","I16";
;
CDS_LIB"standard"
BODY_TYPE"PLUMBING"
HDL_TAP"TRUE";
"B \NAC \NWC"16;
"S \NAC"
BN"6"51;
%"Q_CAP_DIFFBUS"
"2","(3825,2950)","2","pure_quanta","I160";
;
LOCATION"C876"
$SEC"1"
CDS_SEC"1"
VALUE"DIFF BUS_0.22UF"
CDS_LMAN_SYM_OUTLINE"-25,50,25,-50"
CDS_LIB"pure_quanta"
PIN_NAMES_ROTATE"TRUE"
VOLTAGE"6.3V"
MATERIAL"X6S"
PACK_TYPE"C0201"
TOLERANCE"20%"
PART_NUMBER"SP_CH4221MEE01"
LOCATION"C876";
"2"
$PN"2"93;
"1"
$PN"1"121;
%"TAP"
"1","(3100,3150)","2","standard","I161";
;
CDS_LIB"standard"
BODY_TYPE"PLUMBING"
HDL_TAP"TRUE";
"B \NAC \NWC"13;
"S \NAC"
BN"13"99;
%"TAP"
"1","(3100,3350)","2","standard","I162";
;
CDS_LIB"standard"
BODY_TYPE"PLUMBING"
HDL_TAP"TRUE";
"B \NAC \NWC"13;
"S \NAC"
BN"14"100;
%"TAP"
"1","(3100,3550)","2","standard","I163";
;
CDS_LIB"standard"
BODY_TYPE"PLUMBING"
HDL_TAP"TRUE";
"B \NAC \NWC"13;
"S \NAC"
BN"15"98;
%"Q_CAP_DIFFBUS"
"2","(3825,3100)","2","pure_quanta","I164";
;
LOCATION"C875"
$SEC"1"
CDS_SEC"1"
VALUE"DIFF BUS_0.22UF"
CDS_LMAN_SYM_OUTLINE"-25,50,25,-50"
CDS_LIB"pure_quanta"
PIN_NAMES_ROTATE"TRUE"
VOLTAGE"6.3V"
MATERIAL"X6S"
PACK_TYPE"C0201"
TOLERANCE"20%"
PART_NUMBER"SP_CH4221MEE01"
LOCATION"C875";
"2"
$PN"2"90;
"1"
$PN"1"101;
%"Q_CAP_DIFFBUS"
"2","(3825,3150)","2","pure_quanta","I165";
;
LOCATION"C874"
$SEC"1"
CDS_SEC"1"
VALUE"DIFF BUS_0.22UF"
CDS_LMAN_SYM_OUTLINE"-25,50,25,-50"
CDS_LIB"pure_quanta"
PIN_NAMES_ROTATE"TRUE"
VOLTAGE"6.3V"
MATERIAL"X6S"
PACK_TYPE"C0201"
TOLERANCE"20%"
PART_NUMBER"SP_CH4221MEE01"
LOCATION"C874";
"2"
$PN"2"99;
"1"
$PN"1"102;
%"Q_CAP_DIFFBUS"
"2","(3825,3300)","2","pure_quanta","I166";
;
LOCATION"C873"
$SEC"1"
CDS_SEC"1"
VALUE"DIFF BUS_0.22UF"
CDS_LMAN_SYM_OUTLINE"-25,50,25,-50"
CDS_LIB"pure_quanta"
PIN_NAMES_ROTATE"TRUE"
VOLTAGE"6.3V"
MATERIAL"X6S"
PACK_TYPE"C0201"
TOLERANCE"20%"
PART_NUMBER"SP_CH4221MEE01"
LOCATION"C873";
"2"
$PN"2"92;
"1"
$PN"1"128;
%"Q_CAP_DIFFBUS"
"2","(3825,3350)","2","pure_quanta","I167";
;
LOCATION"C872"
$SEC"1"
CDS_SEC"1"
VALUE"DIFF BUS_0.22UF"
CDS_LMAN_SYM_OUTLINE"-25,50,25,-50"
CDS_LIB"pure_quanta"
PIN_NAMES_ROTATE"TRUE"
VOLTAGE"6.3V"
MATERIAL"X6S"
PACK_TYPE"C0201"
TOLERANCE"20%"
PART_NUMBER"SP_CH4221MEE01"
LOCATION"C872";
"2"
$PN"2"100;
"1"
$PN"1"125;
%"Q_CAP_DIFFBUS"
"2","(3825,3500)","2","pure_quanta","I168";
;
LOCATION"C871"
$SEC"1"
CDS_SEC"1"
VALUE"DIFF BUS_0.22UF"
CDS_LMAN_SYM_OUTLINE"-25,50,25,-50"
CDS_LIB"pure_quanta"
PIN_NAMES_ROTATE"TRUE"
VOLTAGE"6.3V"
MATERIAL"X6S"
PACK_TYPE"C0201"
TOLERANCE"20%"
PART_NUMBER"SP_CH4221MEE01"
LOCATION"C871";
"2"
$PN"2"91;
"1"
$PN"1"127;
%"Q_CAP_DIFFBUS"
"2","(3825,3550)","2","pure_quanta","I169";
;
LOCATION"C870"
$SEC"1"
CDS_SEC"1"
MATERIAL"X6S"
VALUE"DIFF BUS_0.22UF"
VOLTAGE"6.3V"
TOLERANCE"20%"
PACK_TYPE"C0201"
CDS_LIB"pure_quanta"
CDS_LMAN_SYM_OUTLINE"-25,50,25,-50"
PIN_NAMES_ROTATE"TRUE"
PART_NUMBER"SP_CH4221MEE01"
LOCATION"C870";
"2"
$PN"2"98;
"1"
$PN"1"126;
%"TAP"
"1","(-1625,1525)","2","standard","I17";
;
CDS_LIB"standard"
BODY_TYPE"PLUMBING"
HDL_TAP"TRUE";
"B \NAC \NWC"16;
"S \NAC"
BN"7"48;
%"TAP"
"1","(4375,175)","0","standard","I170";
;
CDS_LIB"standard"
BODY_TYPE"PLUMBING"
HDL_TAP"TRUE";
"B \NAC \NWC"10;
"S \NAC"
BN"0"129;
%"TAP"
"1","(4375,375)","0","standard","I171";
;
CDS_LIB"standard"
BODY_TYPE"PLUMBING"
HDL_TAP"TRUE";
"B \NAC \NWC"10;
"S \NAC"
BN"1"106;
%"TAP"
"1","(4375,575)","0","standard","I172";
;
CDS_LIB"standard"
BODY_TYPE"PLUMBING"
HDL_TAP"TRUE";
"B \NAC \NWC"10;
"S \NAC"
BN"2"107;
%"TAP"
"1","(4375,975)","0","standard","I173";
;
CDS_LIB"standard"
BODY_TYPE"PLUMBING"
HDL_TAP"TRUE";
"B \NAC \NWC"10;
"S \NAC"
BN"4"112;
%"TAP"
"1","(4375,775)","0","standard","I174";
;
CDS_LIB"standard"
BODY_TYPE"PLUMBING"
HDL_TAP"TRUE";
"B \NAC \NWC"10;
"S \NAC"
BN"3"108;
%"TAP"
"1","(4575,125)","0","standard","I175";
;
CDS_LIB"standard"
BODY_TYPE"PLUMBING"
HDL_TAP"TRUE";
"B \NAC \NWC"9;
"S \NAC"
BN"0"130;
%"TAP"
"1","(4575,325)","0","standard","I176";
;
CDS_LIB"standard"
BODY_TYPE"PLUMBING"
HDL_TAP"TRUE";
"B \NAC \NWC"9;
"S \NAC"
BN"1"131;
%"TAP"
"1","(4575,525)","0","standard","I177";
;
CDS_LIB"standard"
BODY_TYPE"PLUMBING"
HDL_TAP"TRUE";
"B \NAC \NWC"9;
"S \NAC"
BN"2"110;
%"TAP"
"1","(4575,725)","0","standard","I178";
;
CDS_LIB"standard"
BODY_TYPE"PLUMBING"
HDL_TAP"TRUE";
"B \NAC \NWC"9;
"S \NAC"
BN"3"111;
%"TAP"
"1","(4575,925)","0","standard","I179";
;
CDS_LIB"standard"
BODY_TYPE"PLUMBING"
HDL_TAP"TRUE";
"B \NAC \NWC"9;
"S \NAC"
BN"4"109;
%"TAP"
"1","(-1375,1175)","2","standard","I18";
;
CDS_LIB"standard"
BODY_TYPE"PLUMBING"
HDL_TAP"TRUE";
"B \NAC \NWC"15;
"S \NAC"
BN"5"52;
%"TAP"
"1","(4375,1175)","0","standard","I180";
;
CDS_LIB"standard"
BODY_TYPE"PLUMBING"
HDL_TAP"TRUE";
"B \NAC \NWC"10;
"S \NAC"
BN"5"113;
%"TAP"
"1","(4375,1375)","0","standard","I181";
;
CDS_LIB"standard"
BODY_TYPE"PLUMBING"
HDL_TAP"TRUE";
"B \NAC \NWC"10;
"S \NAC"
BN"6"114;
%"TAP"
"1","(4375,1575)","0","standard","I182";
;
CDS_LIB"standard"
BODY_TYPE"PLUMBING"
HDL_TAP"TRUE";
"B \NAC \NWC"10;
"S \NAC"
BN"7"115;
%"TAP"
"1","(4575,1125)","0","standard","I183";
;
CDS_LIB"standard"
BODY_TYPE"PLUMBING"
HDL_TAP"TRUE";
"B \NAC \NWC"9;
"S \NAC"
BN"5"103;
%"TAP"
"1","(4575,1325)","0","standard","I184";
;
CDS_LIB"standard"
BODY_TYPE"PLUMBING"
HDL_TAP"TRUE";
"B \NAC \NWC"9;
"S \NAC"
BN"6"104;
%"TAP"
"1","(4575,1525)","0","standard","I185";
;
CDS_LIB"standard"
BODY_TYPE"PLUMBING"
HDL_TAP"TRUE";
"B \NAC \NWC"9;
"S \NAC"
BN"7"116;
%"TAP"
"1","(4375,2150)","0","standard","I188";
;
CDS_LIB"standard"
BODY_TYPE"PLUMBING"
HDL_TAP"TRUE";
"B \NAC \NWC"12;
"S \NAC"
BN"8"118;
%"TAP"
"1","(4375,2350)","0","standard","I189";
;
CDS_LIB"standard"
BODY_TYPE"PLUMBING"
HDL_TAP"TRUE";
"B \NAC \NWC"12;
"S \NAC"
BN"9"117;
%"TAP"
"1","(-1375,1375)","2","standard","I19";
;
CDS_LIB"standard"
BODY_TYPE"PLUMBING"
HDL_TAP"TRUE";
"B \NAC \NWC"15;
"S \NAC"
BN"6"47;
%"TAP"
"1","(4375,2550)","0","standard","I190";
;
CDS_LIB"standard"
BODY_TYPE"PLUMBING"
HDL_TAP"TRUE";
"B \NAC \NWC"12;
"S \NAC"
BN"10"119;
%"TAP"
"1","(4375,2750)","0","standard","I191";
;
CDS_LIB"standard"
BODY_TYPE"PLUMBING"
HDL_TAP"TRUE";
"B \NAC \NWC"12;
"S \NAC"
BN"11"120;
%"TAP"
"1","(4375,2950)","0","standard","I192";
;
CDS_LIB"standard"
BODY_TYPE"PLUMBING"
HDL_TAP"TRUE";
"B \NAC \NWC"12;
"S \NAC"
BN"12"121;
%"TAP"
"1","(4575,2100)","0","standard","I193";
;
CDS_LIB"standard"
BODY_TYPE"PLUMBING"
HDL_TAP"TRUE";
"B \NAC \NWC"11;
"S \NAC"
BN"8"105;
%"TAP"
"1","(4575,2300)","0","standard","I194";
;
CDS_LIB"standard"
BODY_TYPE"PLUMBING"
HDL_TAP"TRUE";
"B \NAC \NWC"11;
"S \NAC"
BN"9"122;
%"TAP"
"1","(4575,2500)","0","standard","I195";
;
CDS_LIB"standard"
BODY_TYPE"PLUMBING"
HDL_TAP"TRUE";
"B \NAC \NWC"11;
"S \NAC"
BN"10"123;
%"TAP"
"1","(4575,2700)","0","standard","I196";
;
CDS_LIB"standard"
BODY_TYPE"PLUMBING"
HDL_TAP"TRUE";
"B \NAC \NWC"11;
"S \NAC"
BN"11"124;
%"TAP"
"1","(4575,2900)","0","standard","I197";
;
CDS_LIB"standard"
BODY_TYPE"PLUMBING"
HDL_TAP"TRUE";
"B \NAC \NWC"11;
"S \NAC"
BN"12"17;
%"TAP"
"1","(4375,3150)","0","standard","I198";
;
CDS_LIB"standard"
BODY_TYPE"PLUMBING"
HDL_TAP"TRUE";
"B \NAC \NWC"12;
"S \NAC"
BN"13"102;
%"TAP"
"1","(4375,3550)","0","standard","I199";
;
CDS_LIB"standard"
BODY_TYPE"PLUMBING"
HDL_TAP"TRUE";
"B \NAC \NWC"12;
"S \NAC"
BN"15"126;
%"TAP"
"1","(-1375,1575)","2","standard","I20";
;
CDS_LIB"standard"
BODY_TYPE"PLUMBING"
HDL_TAP"TRUE";
"B \NAC \NWC"15;
"S \NAC"
BN"7"53;
%"TAP"
"1","(4375,3350)","0","standard","I200";
;
CDS_LIB"standard"
BODY_TYPE"PLUMBING"
HDL_TAP"TRUE";
"B \NAC \NWC"12;
"S \NAC"
BN"14"125;
%"TAP"
"1","(4575,3100)","0","standard","I201";
;
CDS_LIB"standard"
BODY_TYPE"PLUMBING"
HDL_TAP"TRUE";
"B \NAC \NWC"11;
"S \NAC"
BN"13"101;
%"TAP"
"1","(4575,3300)","0","standard","I202";
;
CDS_LIB"standard"
BODY_TYPE"PLUMBING"
HDL_TAP"TRUE";
"B \NAC \NWC"11;
"S \NAC"
BN"14"128;
%"TAP"
"1","(4575,3500)","0","standard","I203";
;
CDS_LIB"standard"
BODY_TYPE"PLUMBING"
HDL_TAP"TRUE";
"B \NAC \NWC"11;
"S \NAC"
BN"15"127;
%"Q_CAP_DIFFBUS"
"2","(3825,375)","2","pure_quanta","I206";
;
LOCATION"C898"
$SEC"1"
CDS_SEC"1"
VALUE"DIFF BUS_0.22UF"
PIN_NAMES_ROTATE"TRUE"
CDS_LMAN_SYM_OUTLINE"-25,50,25,-50"
CDS_LIB"pure_quanta"
VOLTAGE"6.3V"
MATERIAL"X6S"
PACK_TYPE"C0201"
TOLERANCE"20%"
PART_NUMBER"SP_CH4221MEE01"
LOCATION"C898";
"2"
$PN"2"80;
"1"
$PN"1"106;
%"TAP"
"1","(3100,975)","2","standard","I207";
;
CDS_LIB"standard"
BODY_TYPE"PLUMBING"
HDL_TAP"TRUE";
"B \NAC \NWC"8;
"S \NAC"
BN"4"82;
%"TAP"
"1","(2850,1125)","2","standard","I208";
;
CDS_LIB"standard"
BODY_TYPE"PLUMBING"
HDL_TAP"TRUE";
"B \NAC \NWC"7;
"S \NAC"
BN"5"74;
%"Q_CAP_DIFFBUS"
"2","(-650,125)","2","pure_quanta","I21";
;
LOCATION"C869"
$SEC"1"
CDS_SEC"1"
VALUE"DIFF BUS_0.22UF"
TOLERANCE"20%"
PACK_TYPE"C0201"
MATERIAL"X6S"
VOLTAGE"6.3V"
CDS_LMAN_SYM_OUTLINE"-25,50,25,-50"
CDS_LIB"pure_quanta"
PIN_NAMES_ROTATE"TRUE"
PART_NUMBER"SP_CH4221MEE01"
LOCATION"C869";
"2"
$PN"2"39;
"1"
$PN"1"37;
%"Q_CAP_DIFFBUS"
"2","(-650,175)","2","pure_quanta","I22";
;
LOCATION"C868"
$SEC"1"
CDS_SEC"1"
VALUE"DIFF BUS_0.22UF"
TOLERANCE"20%"
PACK_TYPE"C0201"
MATERIAL"X6S"
VOLTAGE"6.3V"
CDS_LMAN_SYM_OUTLINE"-25,50,25,-50"
CDS_LIB"pure_quanta"
PIN_NAMES_ROTATE"TRUE"
PART_NUMBER"SP_CH4221MEE01"
LOCATION"C868";
"2"
$PN"2"49;
"1"
$PN"1"40;
%"Q_CAP_DIFFBUS"
"2","(-650,325)","2","pure_quanta","I23";
;
LOCATION"C867"
$SEC"1"
CDS_SEC"1"
VALUE"DIFF BUS_0.22UF"
TOLERANCE"20%"
PACK_TYPE"C0201"
MATERIAL"X6S"
VOLTAGE"6.3V"
CDS_LMAN_SYM_OUTLINE"-25,50,25,-50"
CDS_LIB"pure_quanta"
PIN_NAMES_ROTATE"TRUE"
PART_NUMBER"SP_CH4221MEE01"
LOCATION"C867";
"2"
$PN"2"46;
"1"
$PN"1"71;
%"Q_CAP_DIFFBUS"
"2","(-650,375)","2","pure_quanta","I24";
;
LOCATION"C866"
$SEC"1"
CDS_SEC"1"
VALUE"DIFF BUS_0.22UF"
TOLERANCE"20%"
PACK_TYPE"C0201"
MATERIAL"X6S"
VOLTAGE"6.3V"
CDS_LIB"pure_quanta"
CDS_LMAN_SYM_OUTLINE"-25,50,25,-50"
PIN_NAMES_ROTATE"TRUE"
PART_NUMBER"SP_CH4221MEE01"
LOCATION"C866";
"2"
$PN"2"55;
"1"
$PN"1"34;
%"Q_CAP_DIFFBUS"
"2","(-650,575)","2","pure_quanta","I25";
;
LOCATION"C864"
$SEC"1"
CDS_SEC"1"
VALUE"DIFF BUS_0.22UF"
TOLERANCE"20%"
PACK_TYPE"C0201"
MATERIAL"X6S"
VOLTAGE"6.3V"
CDS_LMAN_SYM_OUTLINE"-25,50,25,-50"
CDS_LIB"pure_quanta"
PIN_NAMES_ROTATE"TRUE"
PART_NUMBER"SP_CH4221MEE01"
LOCATION"C864";
"2"
$PN"2"44;
"1"
$PN"1"57;
%"Q_CAP_DIFFBUS"
"2","(-650,525)","2","pure_quanta","I26";
;
LOCATION"C865"
$SEC"1"
CDS_SEC"1"
VALUE"DIFF BUS_0.22UF"
TOLERANCE"20%"
PACK_TYPE"C0201"
MATERIAL"X6S"
VOLTAGE"6.3V"
CDS_LMAN_SYM_OUTLINE"-25,50,25,-50"
CDS_LIB"pure_quanta"
PIN_NAMES_ROTATE"TRUE"
PART_NUMBER"SP_CH4221MEE01"
LOCATION"C865";
"2"
$PN"2"45;
"1"
$PN"1"70;
%"Q_CAP_DIFFBUS"
"2","(-650,725)","2","pure_quanta","I27";
;
LOCATION"C863"
$SEC"1"
CDS_SEC"1"
VALUE"DIFF BUS_0.22UF"
TOLERANCE"20%"
PACK_TYPE"C0201"
MATERIAL"X6S"
VOLTAGE"6.3V"
CDS_LIB"pure_quanta"
CDS_LMAN_SYM_OUTLINE"-25,50,25,-50"
PIN_NAMES_ROTATE"TRUE"
PART_NUMBER"SP_CH4221MEE01"
LOCATION"C863";
"2"
$PN"2"38;
"1"
$PN"1"41;
%"Q_CAP_DIFFBUS"
"2","(-650,775)","2","pure_quanta","I28";
;
LOCATION"C862"
$SEC"1"
CDS_SEC"1"
VALUE"DIFF BUS_0.22UF"
TOLERANCE"20%"
PACK_TYPE"C0201"
MATERIAL"X6S"
VOLTAGE"6.3V"
CDS_LIB"pure_quanta"
CDS_LMAN_SYM_OUTLINE"-25,50,25,-50"
PIN_NAMES_ROTATE"TRUE"
PART_NUMBER"SP_CH4221MEE01"
LOCATION"C862";
"2"
$PN"2"50;
"1"
$PN"1"56;
%"Q_CAP_DIFFBUS"
"2","(-650,925)","2","pure_quanta","I29";
;
LOCATION"C861"
$SEC"1"
CDS_SEC"1"
VALUE"DIFF BUS_0.22UF"
TOLERANCE"20%"
PACK_TYPE"C0201"
MATERIAL"X6S"
VOLTAGE"6.3V"
CDS_LMAN_SYM_OUTLINE"-25,50,25,-50"
CDS_LIB"pure_quanta"
PIN_NAMES_ROTATE"TRUE"
PART_NUMBER"SP_CH4221MEE01"
LOCATION"C861";
"2"
$PN"2"54;
"1"
$PN"1"33;
%"Q_CAP_DIFFBUS"
"2","(-650,975)","2","pure_quanta","I30";
;
LOCATION"C860"
$SEC"1"
CDS_SEC"1"
VALUE"DIFF BUS_0.22UF"
TOLERANCE"20%"
PACK_TYPE"C0201"
MATERIAL"X6S"
VOLTAGE"6.3V"
CDS_LMAN_SYM_OUTLINE"-25,50,25,-50"
CDS_LIB"pure_quanta"
PIN_NAMES_ROTATE"TRUE"
PART_NUMBER"SP_CH4221MEE01"
LOCATION"C860";
"2"
$PN"2"43;
"1"
$PN"1"32;
%"TAP"
"1","(-100,175)","0","standard","I31";
;
CDS_LIB"standard"
BODY_TYPE"PLUMBING"
HDL_TAP"TRUE";
"B \NAC \NWC"6;
"S \NAC"
BN"0"40;
%"TAP"
"1","(-100,375)","0","standard","I32";
;
CDS_LIB"standard"
BODY_TYPE"PLUMBING"
HDL_TAP"TRUE";
"B \NAC \NWC"6;
"S \NAC"
BN"1"34;
%"TAP"
"1","(-100,575)","0","standard","I33";
;
CDS_LIB"standard"
BODY_TYPE"PLUMBING"
HDL_TAP"TRUE";
"B \NAC \NWC"6;
"S \NAC"
BN"2"57;
%"TAP"
"1","(-100,775)","0","standard","I34";
;
CDS_LIB"standard"
BODY_TYPE"PLUMBING"
HDL_TAP"TRUE";
"B \NAC \NWC"6;
"S \NAC"
BN"3"56;
%"TAP"
"1","(-100,975)","0","standard","I35";
;
CDS_LIB"standard"
BODY_TYPE"PLUMBING"
HDL_TAP"TRUE";
"B \NAC \NWC"6;
"S \NAC"
BN"4"32;
%"Q_CAP_DIFFBUS"
"2","(-650,1125)","2","pure_quanta","I36";
;
LOCATION"C859"
$SEC"1"
CDS_SEC"1"
VALUE"DIFF BUS_0.22UF"
TOLERANCE"20%"
PACK_TYPE"C0201"
MATERIAL"X6S"
VOLTAGE"6.3V"
CDS_LMAN_SYM_OUTLINE"-25,50,25,-50"
CDS_LIB"pure_quanta"
PIN_NAMES_ROTATE"TRUE"
PART_NUMBER"SP_CH4221MEE01"
LOCATION"C859";
"2"
$PN"2"42;
"1"
$PN"1"72;
%"Q_CAP_DIFFBUS"
"2","(-650,1175)","2","pure_quanta","I37";
;
LOCATION"C858"
$SEC"1"
CDS_SEC"1"
VALUE"DIFF BUS_0.22UF"
TOLERANCE"20%"
PACK_TYPE"C0201"
MATERIAL"X6S"
VOLTAGE"6.3V"
CDS_LMAN_SYM_OUTLINE"-25,50,25,-50"
CDS_LIB"pure_quanta"
PIN_NAMES_ROTATE"TRUE"
PART_NUMBER"SP_CH4221MEE01"
LOCATION"C858";
"2"
$PN"2"52;
"1"
$PN"1"135;
%"Q_CAP_DIFFBUS"
"2","(-650,1325)","2","pure_quanta","I38";
;
LOCATION"C857"
$SEC"1"
CDS_SEC"1"
VALUE"DIFF BUS_0.22UF"
TOLERANCE"20%"
PACK_TYPE"C0201"
MATERIAL"X6S"
VOLTAGE"6.3V"
CDS_LMAN_SYM_OUTLINE"-25,50,25,-50"
CDS_LIB"pure_quanta"
PIN_NAMES_ROTATE"TRUE"
PART_NUMBER"SP_CH4221MEE01"
LOCATION"C857";
"2"
$PN"2"51;
"1"
$PN"1"136;
%"Q_CAP_DIFFBUS"
"2","(-650,1375)","2","pure_quanta","I39";
;
LOCATION"C856"
$SEC"1"
CDS_SEC"1"
VALUE"DIFF BUS_0.22UF"
TOLERANCE"20%"
PACK_TYPE"C0201"
MATERIAL"X6S"
VOLTAGE"6.3V"
CDS_LMAN_SYM_OUTLINE"-25,50,25,-50"
CDS_LIB"pure_quanta"
PIN_NAMES_ROTATE"TRUE"
PART_NUMBER"SP_CH4221MEE01"
LOCATION"C856";
"2"
$PN"2"47;
"1"
$PN"1"58;
%"Q_CAP_DIFFBUS"
"2","(-650,1525)","2","pure_quanta","I40";
;
LOCATION"C855"
$SEC"1"
CDS_SEC"1"
VALUE"DIFF BUS_0.22UF"
TOLERANCE"20%"
PACK_TYPE"C0201"
MATERIAL"X6S"
VOLTAGE"6.3V"
CDS_LMAN_SYM_OUTLINE"-25,50,25,-50"
CDS_LIB"pure_quanta"
PIN_NAMES_ROTATE"TRUE"
PART_NUMBER"SP_CH4221MEE01"
LOCATION"C855";
"2"
$PN"2"48;
"1"
$PN"1"35;
%"Q_CAP_DIFFBUS"
"2","(-650,1575)","2","pure_quanta","I41";
;
LOCATION"C854"
$SEC"1"
CDS_SEC"1"
VALUE"DIFF BUS_0.22UF"
TOLERANCE"20%"
PACK_TYPE"C0201"
MATERIAL"X6S"
VOLTAGE"6.3V"
CDS_LIB"pure_quanta"
CDS_LMAN_SYM_OUTLINE"-25,50,25,-50"
PIN_NAMES_ROTATE"TRUE"
PART_NUMBER"SP_CH4221MEE01"
LOCATION"C854";
"2"
$PN"2"53;
"1"
$PN"1"36;
%"TAP"
"1","(-100,1375)","0","standard","I42";
;
CDS_LIB"standard"
BODY_TYPE"PLUMBING"
HDL_TAP"TRUE";
"B \NAC \NWC"6;
"S \NAC"
BN"6"58;
%"TAP"
"1","(-100,1175)","0","standard","I43";
;
CDS_LIB"standard"
BODY_TYPE"PLUMBING"
HDL_TAP"TRUE";
"B \NAC \NWC"6;
"S \NAC"
BN"5"135;
%"TAP"
"1","(-100,1575)","0","standard","I44";
;
CDS_LIB"standard"
BODY_TYPE"PLUMBING"
HDL_TAP"TRUE";
"B \NAC \NWC"6;
"S \NAC"
BN"7"36;
%"TAP"
"1","(-1625,2100)","2","standard","I45";
;
CDS_LIB"standard"
BODY_TYPE"PLUMBING"
HDL_TAP"TRUE";
"B \NAC \NWC"4;
"S \NAC"
BN"8"21;
%"TAP"
"1","(-1625,2300)","2","standard","I46";
;
CDS_LIB"standard"
BODY_TYPE"PLUMBING"
HDL_TAP"TRUE";
"B \NAC \NWC"4;
"S \NAC"
BN"9"27;
%"TAP"
"1","(-1625,2500)","2","standard","I47";
;
CDS_LIB"standard"
BODY_TYPE"PLUMBING"
HDL_TAP"TRUE";
"B \NAC \NWC"4;
"S \NAC"
BN"10"26;
%"TAP"
"1","(-1625,2700)","2","standard","I48";
;
CDS_LIB"standard"
BODY_TYPE"PLUMBING"
HDL_TAP"TRUE";
"B \NAC \NWC"4;
"S \NAC"
BN"11"62;
%"TAP"
"1","(-1625,2900)","2","standard","I49";
;
CDS_LIB"standard"
BODY_TYPE"PLUMBING"
HDL_TAP"TRUE";
"B \NAC \NWC"4;
"S \NAC"
BN"12"137;
%"TAP"
"1","(-1625,125)","2","standard","I5";
;
CDS_LIB"standard"
BODY_TYPE"PLUMBING"
HDL_TAP"TRUE";
"B \NAC \NWC"16;
"S \NAC"
BN"0"39;
%"TAP"
"1","(-1375,2150)","2","standard","I50";
;
CDS_LIB"standard"
BODY_TYPE"PLUMBING"
HDL_TAP"TRUE";
"B \NAC \NWC"3;
"S \NAC"
BN"8"20;
%"TAP"
"1","(-1375,2350)","2","standard","I51";
;
CDS_LIB"standard"
BODY_TYPE"PLUMBING"
HDL_TAP"TRUE";
"B \NAC \NWC"3;
"S \NAC"
BN"9"59;
%"TAP"
"1","(-1375,2550)","2","standard","I52";
;
CDS_LIB"standard"
BODY_TYPE"PLUMBING"
HDL_TAP"TRUE";
"B \NAC \NWC"3;
"S \NAC"
BN"10"25;
%"TAP"
"1","(-1375,2750)","2","standard","I53";
;
CDS_LIB"standard"
BODY_TYPE"PLUMBING"
HDL_TAP"TRUE";
"B \NAC \NWC"3;
"S \NAC"
BN"11"31;
%"TAP"
"1","(-1375,2950)","2","standard","I54";
;
CDS_LIB"standard"
BODY_TYPE"PLUMBING"
HDL_TAP"TRUE";
"B \NAC \NWC"3;
"S \NAC"
BN"12"138;
%"TAP"
"1","(-1625,3500)","2","standard","I55";
;
CDS_LIB"standard"
BODY_TYPE"PLUMBING"
HDL_TAP"TRUE";
"B \NAC \NWC"4;
"S \NAC"
BN"15"29;
%"TAP"
"1","(-1625,3300)","2","standard","I56";
;
CDS_LIB"standard"
BODY_TYPE"PLUMBING"
HDL_TAP"TRUE";
"B \NAC \NWC"4;
"S \NAC"
BN"14"30;
%"TAP"
"1","(-1625,3100)","2","standard","I57";
;
CDS_LIB"standard"
BODY_TYPE"PLUMBING"
HDL_TAP"TRUE";
"B \NAC \NWC"4;
"S \NAC"
BN"13"63;
%"TAP"
"1","(-1375,3150)","2","standard","I58";
;
CDS_LIB"standard"
BODY_TYPE"PLUMBING"
HDL_TAP"TRUE";
"B \NAC \NWC"3;
"S \NAC"
BN"13"60;
%"TAP"
"1","(-1375,3350)","2","standard","I59";
;
CDS_LIB"standard"
BODY_TYPE"PLUMBING"
HDL_TAP"TRUE";
"B \NAC \NWC"3;
"S \NAC"
BN"14"61;
%"TAP"
"1","(-1625,325)","2","standard","I6";
;
CDS_LIB"standard"
BODY_TYPE"PLUMBING"
HDL_TAP"TRUE";
"B \NAC \NWC"16;
"S \NAC"
BN"1"46;
%"TAP"
"1","(-1375,3550)","2","standard","I60";
;
CDS_LIB"standard"
BODY_TYPE"PLUMBING"
HDL_TAP"TRUE";
"B \NAC \NWC"3;
"S \NAC"
BN"15"28;
%"Q_CAP_DIFFBUS"
"2","(-650,2150)","2","pure_quanta","I61";
;
LOCATION"C852"
$SEC"1"
CDS_SEC"1"
VALUE"DIFF BUS_0.22UF"
TOLERANCE"20%"
PACK_TYPE"C0201"
MATERIAL"X6S"
VOLTAGE"6.3V"
PIN_NAMES_ROTATE"TRUE"
CDS_LIB"pure_quanta"
CDS_LMAN_SYM_OUTLINE"-25,50,25,-50"
PART_NUMBER"SP_CH4221MEE01"
LOCATION"C852";
"2"
$PN"2"20;
"1"
$PN"1"65;
%"Q_CAP_DIFFBUS"
"2","(-650,2100)","2","pure_quanta","I62";
;
LOCATION"C853"
$SEC"1"
CDS_SEC"1"
VALUE"DIFF BUS_0.22UF"
TOLERANCE"20%"
PACK_TYPE"C0201"
MATERIAL"X6S"
VOLTAGE"6.3V"
PIN_NAMES_ROTATE"TRUE"
CDS_LIB"pure_quanta"
CDS_LMAN_SYM_OUTLINE"-25,50,25,-50"
PART_NUMBER"SP_CH4221MEE01"
LOCATION"C853";
"2"
$PN"2"21;
"1"
$PN"1"22;
%"Q_CAP_DIFFBUS"
"2","(-650,2300)","2","pure_quanta","I63";
;
LOCATION"C851"
$SEC"1"
CDS_SEC"1"
VALUE"DIFF BUS_0.22UF"
TOLERANCE"20%"
PACK_TYPE"C0201"
MATERIAL"X6S"
VOLTAGE"6.3V"
PIN_NAMES_ROTATE"TRUE"
CDS_LIB"pure_quanta"
CDS_LMAN_SYM_OUTLINE"-25,50,25,-50"
PART_NUMBER"SP_CH4221MEE01"
LOCATION"C851";
"2"
$PN"2"27;
"1"
$PN"1"19;
%"Q_CAP_DIFFBUS"
"2","(-650,2350)","2","pure_quanta","I64";
;
LOCATION"C850"
$SEC"1"
CDS_SEC"1"
VALUE"DIFF BUS_0.22UF"
TOLERANCE"20%"
PACK_TYPE"C0201"
MATERIAL"X6S"
VOLTAGE"6.3V"
PIN_NAMES_ROTATE"TRUE"
CDS_LMAN_SYM_OUTLINE"-25,50,25,-50"
CDS_LIB"pure_quanta"
PART_NUMBER"SP_CH4221MEE01"
LOCATION"C850";
"2"
$PN"2"59;
"1"
$PN"1"64;
%"Q_CAP_DIFFBUS"
"2","(-650,2500)","2","pure_quanta","I65";
;
LOCATION"C849"
$SEC"1"
CDS_SEC"1"
VALUE"DIFF BUS_0.22UF"
TOLERANCE"20%"
PACK_TYPE"C0201"
MATERIAL"X6S"
VOLTAGE"6.3V"
PIN_NAMES_ROTATE"TRUE"
CDS_LIB"pure_quanta"
CDS_LMAN_SYM_OUTLINE"-25,50,25,-50"
PART_NUMBER"SP_CH4221MEE01"
LOCATION"C849";
"2"
$PN"2"26;
"1"
$PN"1"68;
%"Q_CAP_DIFFBUS"
"2","(-650,2550)","2","pure_quanta","I66";
;
LOCATION"C848"
$SEC"1"
CDS_SEC"1"
VALUE"DIFF BUS_0.22UF"
TOLERANCE"20%"
PACK_TYPE"C0201"
MATERIAL"X6S"
VOLTAGE"6.3V"
PIN_NAMES_ROTATE"TRUE"
CDS_LIB"pure_quanta"
CDS_LMAN_SYM_OUTLINE"-25,50,25,-50"
PART_NUMBER"SP_CH4221MEE01"
LOCATION"C848";
"2"
$PN"2"25;
"1"
$PN"1"66;
%"Q_CAP_DIFFBUS"
"2","(-650,2700)","2","pure_quanta","I67";
;
LOCATION"C847"
$SEC"1"
CDS_SEC"1"
VALUE"DIFF BUS_0.22UF"
TOLERANCE"20%"
PACK_TYPE"C0201"
MATERIAL"X6S"
VOLTAGE"6.3V"
PIN_NAMES_ROTATE"TRUE"
CDS_LMAN_SYM_OUTLINE"-25,50,25,-50"
CDS_LIB"pure_quanta"
PART_NUMBER"SP_CH4221MEE01"
LOCATION"C847";
"2"
$PN"2"62;
"1"
$PN"1"69;
%"Q_CAP_DIFFBUS"
"2","(-650,2750)","2","pure_quanta","I68";
;
LOCATION"C846"
$SEC"1"
CDS_SEC"1"
VALUE"DIFF BUS_0.22UF"
TOLERANCE"20%"
PACK_TYPE"C0201"
MATERIAL"X6S"
VOLTAGE"6.3V"
PIN_NAMES_ROTATE"TRUE"
CDS_LMAN_SYM_OUTLINE"-25,50,25,-50"
CDS_LIB"pure_quanta"
PART_NUMBER"SP_CH4221MEE01"
LOCATION"C846";
"2"
$PN"2"31;
"1"
$PN"1"24;
%"Q_CAP_DIFFBUS"
"2","(-650,2900)","2","pure_quanta","I69";
;
LOCATION"C845"
$SEC"1"
CDS_SEC"1"
VALUE"DIFF BUS_0.22UF"
TOLERANCE"20%"
PACK_TYPE"C0201"
MATERIAL"X6S"
VOLTAGE"6.3V"
PIN_NAMES_ROTATE"TRUE"
CDS_LIB"pure_quanta"
CDS_LMAN_SYM_OUTLINE"-25,50,25,-50"
PART_NUMBER"SP_CH4221MEE01"
LOCATION"C845";
"2"
$PN"2"137;
"1"
$PN"1"23;
%"TAP"
"1","(-1625,525)","2","standard","I7";
;
CDS_LIB"standard"
BODY_TYPE"PLUMBING"
HDL_TAP"TRUE";
"B \NAC \NWC"16;
"S \NAC"
BN"2"45;
%"Q_CAP_DIFFBUS"
"2","(-650,2950)","2","pure_quanta","I70";
;
LOCATION"C844"
$SEC"1"
CDS_SEC"1"
VALUE"DIFF BUS_0.22UF"
TOLERANCE"20%"
PACK_TYPE"C0201"
MATERIAL"X6S"
VOLTAGE"6.3V"
PIN_NAMES_ROTATE"TRUE"
CDS_LIB"pure_quanta"
CDS_LMAN_SYM_OUTLINE"-25,50,25,-50"
PART_NUMBER"SP_CH4221MEE01"
LOCATION"C844";
"2"
$PN"2"138;
"1"
$PN"1"67;
%"TAP"
"1","(-100,2150)","0","standard","I71";
;
CDS_LIB"standard"
BODY_TYPE"PLUMBING"
HDL_TAP"TRUE";
"B \NAC \NWC"1;
"S \NAC"
BN"8"65;
%"TAP"
"1","(-100,2350)","0","standard","I72";
;
CDS_LIB"standard"
BODY_TYPE"PLUMBING"
HDL_TAP"TRUE";
"B \NAC \NWC"1;
"S \NAC"
BN"9"64;
%"TAP"
"1","(-100,2550)","0","standard","I73";
;
CDS_LIB"standard"
BODY_TYPE"PLUMBING"
HDL_TAP"TRUE";
"B \NAC \NWC"1;
"S \NAC"
BN"10"66;
%"TAP"
"1","(-100,2750)","0","standard","I74";
;
CDS_LIB"standard"
BODY_TYPE"PLUMBING"
HDL_TAP"TRUE";
"B \NAC \NWC"1;
"S \NAC"
BN"11"24;
%"TAP"
"1","(-100,2950)","0","standard","I75";
;
CDS_LIB"standard"
BODY_TYPE"PLUMBING"
HDL_TAP"TRUE";
"B \NAC \NWC"1;
"S \NAC"
BN"12"67;
%"Q_CAP_DIFFBUS"
"2","(-650,3150)","2","pure_quanta","I76";
;
LOCATION"C842"
$SEC"1"
CDS_SEC"1"
VALUE"DIFF BUS_0.22UF"
TOLERANCE"20%"
PACK_TYPE"C0201"
MATERIAL"X6S"
VOLTAGE"6.3V"
PIN_NAMES_ROTATE"TRUE"
CDS_LIB"pure_quanta"
CDS_LMAN_SYM_OUTLINE"-25,50,25,-50"
PART_NUMBER"SP_CH4221MEE01"
LOCATION"C842";
"2"
$PN"2"60;
"1"
$PN"1"140;
%"Q_CAP_DIFFBUS"
"2","(-650,3100)","2","pure_quanta","I77";
;
LOCATION"C843"
$SEC"1"
CDS_SEC"1"
VALUE"DIFF BUS_0.22UF"
TOLERANCE"20%"
PACK_TYPE"C0201"
MATERIAL"X6S"
VOLTAGE"6.3V"
PIN_NAMES_ROTATE"TRUE"
CDS_LIB"pure_quanta"
CDS_LMAN_SYM_OUTLINE"-25,50,25,-50"
PART_NUMBER"SP_CH4221MEE01"
LOCATION"C843";
"2"
$PN"2"63;
"1"
$PN"1"139;
%"Q_CAP_DIFFBUS"
"2","(-650,3300)","2","pure_quanta","I78";
;
LOCATION"C841"
$SEC"1"
CDS_SEC"1"
VALUE"DIFF BUS_0.22UF"
TOLERANCE"20%"
PACK_TYPE"C0201"
MATERIAL"X6S"
VOLTAGE"6.3V"
PIN_NAMES_ROTATE"TRUE"
CDS_LIB"pure_quanta"
CDS_LMAN_SYM_OUTLINE"-25,50,25,-50"
PART_NUMBER"SP_CH4221MEE01"
LOCATION"C841";
"2"
$PN"2"30;
"1"
$PN"1"141;
%"Q_CAP_DIFFBUS"
"2","(-650,3350)","2","pure_quanta","I79";
;
LOCATION"C840"
$SEC"1"
CDS_SEC"1"
VALUE"DIFF BUS_0.22UF"
TOLERANCE"20%"
PACK_TYPE"C0201"
MATERIAL"X6S"
VOLTAGE"6.3V"
PIN_NAMES_ROTATE"TRUE"
CDS_LIB"pure_quanta"
CDS_LMAN_SYM_OUTLINE"-25,50,25,-50"
PART_NUMBER"SP_CH4221MEE01"
LOCATION"C840";
"2"
$PN"2"61;
"1"
$PN"1"142;
%"TAP"
"1","(-1625,725)","2","standard","I8";
;
CDS_LIB"standard"
BODY_TYPE"PLUMBING"
HDL_TAP"TRUE";
"B \NAC \NWC"16;
"S \NAC"
BN"3"38;
%"Q_CAP_DIFFBUS"
"2","(-650,3550)","2","pure_quanta","I80";
;
LOCATION"C838"
$SEC"1"
CDS_SEC"1"
VALUE"DIFF BUS_0.22UF"
PACK_TYPE"C0201"
TOLERANCE"20%"
MATERIAL"X6S"
VOLTAGE"6.3V"
PIN_NAMES_ROTATE"TRUE"
CDS_LMAN_SYM_OUTLINE"-25,50,25,-50"
CDS_LIB"pure_quanta"
PART_NUMBER"SP_CH4221MEE01"
LOCATION"C838";
"2"
$PN"2"28;
"1"
$PN"1"144;
%"Q_CAP_DIFFBUS"
"2","(-650,3500)","2","pure_quanta","I81";
;
LOCATION"C839"
$SEC"1"
CDS_SEC"1"
VALUE"DIFF BUS_0.22UF"
TOLERANCE"20%"
PACK_TYPE"C0201"
MATERIAL"X6S"
VOLTAGE"6.3V"
PIN_NAMES_ROTATE"TRUE"
CDS_LIB"pure_quanta"
CDS_LMAN_SYM_OUTLINE"-25,50,25,-50"
PART_NUMBER"SP_CH4221MEE01"
LOCATION"C839";
"2"
$PN"2"29;
"1"
$PN"1"143;
%"TAP"
"1","(-100,3550)","0","standard","I82";
;
CDS_LIB"standard"
BODY_TYPE"PLUMBING"
HDL_TAP"TRUE";
"B \NAC \NWC"1;
"S \NAC"
BN"15"144;
%"TAP"
"1","(-100,3350)","0","standard","I83";
;
CDS_LIB"standard"
BODY_TYPE"PLUMBING"
HDL_TAP"TRUE";
"B \NAC \NWC"1;
"S \NAC"
BN"14"142;
%"TAP"
"1","(-100,3150)","0","standard","I84";
;
CDS_LIB"standard"
BODY_TYPE"PLUMBING"
HDL_TAP"TRUE";
"B \NAC \NWC"1;
"S \NAC"
BN"13"140;
%"TAP"
"1","(100,125)","0","standard","I85";
;
CDS_LIB"standard"
BODY_TYPE"PLUMBING"
HDL_TAP"TRUE";
"B \NAC \NWC"5;
"S \NAC"
BN"0"37;
%"TAP"
"1","(100,325)","0","standard","I86";
;
CDS_LIB"standard"
BODY_TYPE"PLUMBING"
HDL_TAP"TRUE";
"B \NAC \NWC"5;
"S \NAC"
BN"1"71;
%"TAP"
"1","(100,525)","0","standard","I87";
;
CDS_LIB"standard"
BODY_TYPE"PLUMBING"
HDL_TAP"TRUE";
"B \NAC \NWC"5;
"S \NAC"
BN"2"70;
%"TAP"
"1","(100,725)","0","standard","I88";
;
CDS_LIB"standard"
BODY_TYPE"PLUMBING"
HDL_TAP"TRUE";
"B \NAC \NWC"5;
"S \NAC"
BN"3"41;
%"TAP"
"1","(100,925)","0","standard","I89";
;
CDS_LIB"standard"
BODY_TYPE"PLUMBING"
HDL_TAP"TRUE";
"B \NAC \NWC"5;
"S \NAC"
BN"4"33;
%"TAP"
"1","(-1625,925)","2","standard","I9";
;
CDS_LIB"standard"
BODY_TYPE"PLUMBING"
HDL_TAP"TRUE";
"B \NAC \NWC"16;
"S \NAC"
BN"4"54;
%"TAP"
"1","(100,1125)","0","standard","I90";
;
CDS_LIB"standard"
BODY_TYPE"PLUMBING"
HDL_TAP"TRUE";
"B \NAC \NWC"5;
"S \NAC"
BN"5"72;
%"TAP"
"1","(100,1325)","0","standard","I91";
;
CDS_LIB"standard"
BODY_TYPE"PLUMBING"
HDL_TAP"TRUE";
"B \NAC \NWC"5;
"S \NAC"
BN"6"136;
%"TAP"
"1","(100,1525)","0","standard","I92";
;
CDS_LIB"standard"
BODY_TYPE"PLUMBING"
HDL_TAP"TRUE";
"B \NAC \NWC"5;
"S \NAC"
BN"7"35;
%"TAP"
"1","(100,2100)","0","standard","I97";
;
CDS_LIB"standard"
BODY_TYPE"PLUMBING"
HDL_TAP"TRUE";
"B \NAC \NWC"2;
"S \NAC"
BN"8"22;
%"TAP"
"1","(100,2300)","0","standard","I98";
;
CDS_LIB"standard"
BODY_TYPE"PLUMBING"
HDL_TAP"TRUE";
"B \NAC \NWC"2;
"S \NAC"
BN"9"19;
%"TAP"
"1","(100,2500)","0","standard","I99";
;
CDS_LIB"standard"
BODY_TYPE"PLUMBING"
HDL_TAP"TRUE";
"B \NAC \NWC"2;
"S \NAC"
BN"10"68;
END.
